# MB_14L_stackup.xlsx — 工作表2 (pcb-stackup)
|  |  |  |  |  | Version |  |  |  |  |  |  |  |  |  |  |  |  |  |  |  |  |  |  |  |  |  |  |  |  |  |  |  |  |  |  |  |  |  |  |  |
| Board Number: |  | 15126-SC |  |  | 01 |  |  |  |  |  |  |  |  |  |  |  |  |  |  |  |  |  |  |  |  |  |  |  |  |  |  |  |  |  |  |  |  |  |  |  |
| Project name: |  | Tioga Pass |  |  |  |  |  |  |  |  |  |  |  |  |  |  |  |  |  |  |  |  |  |  |  |  |  |  |  |  |  |  |  |  |  |  |  |  |  |  |
| Model Name: |  | Main Board |  |  |  |  |  |  |  |  |  |  |  |  |  |  |  |  |  |  |  |  |  |  |  |  |  |  |  |  |  |  |  |  |  |  |  |  |  |  |
| Layer Count: |  | 14 Layer |  |  |  |  |  |  |  |  |  |  |  |  |  |  |  |  |  |  |  |  |  |  |  |  |  |  |  |  |  |  |  |  |  |  |  |  |  |  |
| Date: |  | 2016-08-03 00:00:00 |  |  |  |  |  |  |  |  |  |  |  |  |  |  |  |  |  |  |  |  |  |  |  |  |  |  |  |  |  |  |  |  |  |  |  |  |  |  |
| Material: |  | IT170GRA1 |  |  |  |  |  | Single Ended Type(mil) |  |  |  |  |  |  |  |  | Differential Type(mil) |  |  |  |  |  |  |  |  |  |  |  |  |  |  |  |  |  |  |  |  |  |  |  |
| Gold Finger(Y/N): |  | N |  |  |  |  | Imp | 40 |  |  |  | 50 |  |  |  | Imp | 73 |  |  |  |  |  | 85 |  |  |  |  |  | 95 |  |  |  |  |  | 100 |  |  |  |  |  |
| Customer: |  | XXXXX |  |  |  |  | Variation | Inner/Outer+/-5ohm |  |  |  | Inner/Outer+/-5ohm |  |  |  | Variation | Inner/Outer+/-10% |  |  |  |  |  | Inner/Outer+/-10% |  |  |  |  |  | Inner/Outer+/-10% |  |  |  |  |  | Inner/Outer+/-10% |  |  |  |  |  |
| EE engineer |  | <name> |  |  |  |  | Bus | DDR4 DQ/CTRL/CMD/DQS/CLK |  |  |  | Misc. |  |  |  | Bus | DDR4 CLK, DDR4 DQS |  |  |  |  |  | QPI, PCIe, DMI2, Clock, USB, SATA |  |  |  |  |  | LAN (MDI) |  |  |  |  |  | MII |  |  |  |  |  |
| SI Engineer |  | <name> |  |  |  |  |  |  |  |  |  |  |  |  |  |  |  |  |  |  |  |  |  |  |  |  |  |  |  |  |  |  |  |  |  |  |  |  |  |  |
|  |  |  |  |  |  |  | Type | SE |  |  |  | SE |  |  |  | Type | DP |  |  |  |  |  | DP |  |  |  |  |  | DP |  |  |  |  |  | DP |  |  |  |  |  |
| Layer |  |  | Thickness | Glass/Copper Style | Er | Df(1G) | Layers | 1,3,5,10,12,14 |  |  |  | 1,3,5,10,12,14 |  |  |  | Layers | 1,3,5,10,12,14 |  |  |  |  |  | 1,3,5,10,12,14 |  |  |  |  |  | 1,3,5,10,12,14 |  |  |  |  |  | 1,3,5,10,12,14 |  |  |  |  |  |
|  |  | Cu oz | Wiwynn |  | Wiwynn |  |  | Wiwynn |  |  |  | Wiwynn |  |  |  |  | Wiwynn |  |  |  |  |  | Wiwynn |  |  |  |  |  | Wiwynn |  |  |  |  |  | Wiwynn |  |  |  |  |  |
|  | Mask |  | 0.5 |  | 3.4 |  |  | Width | Imp | Width | Imp | Width | Imp | Width | Imp |  | Width | Space | Imp | Width | Space | Imp | Width | Space | Imp | Width | Space | Imp | Width | Space | Imp | Width | Space | Imp | Width | Space | Imp | Width | Space | Imp |
| Top | Signal | 0.5 oz+plating | 1.8 |  |  |  | S1 | 6.5(L2) |  |  |  | 4.25(L2) |  |  |  | S1 | 6.5(L2) | 5 |  |  |  |  | 4.5(L2) | 5 |  |  |  |  | 4.6(L2) | 13.5 |  |  |  |  | 3.95(L2) | 14.05 |  |  |  |  |
|  | Prepreg |  | 2.7 | 1080, 62% | 3.7 |  |  |  |  |  |  |  |  |  |  |  |  |  |  |  |  |  |  |  |  |  |  |  |  |  |  |  |  |  |  |  |  |  |  |  |
| L2 | GND | 1 oz | 1.3 |  |  |  | G2 | reference layer |  |  |  | reference layer |  |  |  | G2 | reference layer |  |  |  |  |  | reference layer |  |  |  |  |  | reference layer |  |  |  |  |  | reference layer |  |  |  |  |  |
|  | Core |  | 10 | 2116, 50.2%*2 | 3.8 |  |  |  |  |  |  |  |  |  |  |  |  |  |  |  |  |  |  |  |  |  |  |  |  |  |  |  |  |  |  |  |  |  |  |  |
| L3 | Signal | 1 oz | 1.3 |  |  |  | S3 | 5.6(L2/L4) |  |  |  | 3.52(L2/L4) |  |  |  | S3 | 5.6(L2/L4) | 5 |  |  |  |  | 4.5(L2/L4) | 7 |  |  |  |  | 4.02(L2/L4) | 11.98 |  |  |  |  | 3.99(L2/L4) | 12.52 |  |  |  |  |
|  | Prepreg |  | 3 | 106, 71.5%*2 | 3.6 |  |  |  |  |  |  |  |  |  |  |  |  |  |  |  |  |  |  |  |  |  |  |  |  |  |  |  |  |  |  |  |  |  |  |  |
| L4 | GND | 1 oz | 1.3 |  |  |  | G4 | reference layer |  |  |  | reference layer |  |  |  | G4 | reference layer |  |  |  |  |  | reference layer |  |  |  |  |  | reference layer |  |  |  |  |  | reference layer |  |  |  |  |  |
|  | Core |  | 10 | 2116, 50.2%*2 | 3.8 |  |  |  |  |  |  |  |  |  |  |  |  |  |  |  |  |  |  |  |  |  |  |  |  |  |  |  |  |  |  |  |  |  |  |  |
| L5 | Signal | 1 oz | 1.3 |  |  |  | S5 | 5.6(L4/L6) |  |  |  | 3.52(L4/L6) |  |  |  | S5 | 5.6(L4/L6) | 5 |  |  |  |  | 4.5(L4/L6) | 7 |  |  |  |  | 4.02(L4/L6) | 11.98 |  |  |  |  | 3.99(L4/L6) | 12.52 |  |  |  |  |
|  | Prepreg |  | 3 | 106, 71.5%*2 | 3.6 |  |  |  |  |  |  |  |  |  |  |  |  |  |  |  |  |  |  |  |  |  |  |  |  |  |  |  |  |  |  |  |  |  |  |  |
| L6 | GND | 1 oz | 1.3 |  |  |  | G6 | reference layer |  |  |  | reference layer |  |  |  | G6 | reference layer |  |  |  |  |  | reference layer |  |  |  |  |  | reference layer |  |  |  |  |  | reference layer |  |  |  |  |  |
|  | Core |  | 3 | 1086, 57.9%*1 | 3.7 |  |  |  |  |  |  |  |  |  |  |  |  |  |  |  |  |  |  |  |  |  |  |  |  |  |  |  |  |  |  |  |  |  |  |  |
| L7 | POWER | 2 oz | 2.6 |  |  |  | P7 | reference layer |  |  |  | reference layer |  |  |  | P7 | reference layer |  |  |  |  |  | reference layer |  |  |  |  |  | reference layer |  |  |  |  |  | reference layer |  |  |  |  |  |
|  | Prepreg |  | 5.9 | 1080, 68%*2 | 3.7 |  |  |  |  |  |  |  |  |  |  |  |  |  |  |  |  |  |  |  |  |  |  |  |  |  |  |  |  |  |  |  |  |  |  |  |
| L8 | POWER | 2 oz | 2.6 |  |  |  | P8 | reference layer |  |  |  | reference layer |  |  |  | P8 | reference layer |  |  |  |  |  | reference layer |  |  |  |  |  | reference layer |  |  |  |  |  | reference layer |  |  |  |  |  |
|  | Core |  | 3 | 1086, 57.9%*1 | 3.7 |  |  |  |  |  |  |  |  |  |  |  |  |  |  |  |  |  |  |  |  |  |  |  |  |  |  |  |  |  |  |  |  |  |  |  |
| L9 | GND | 1 oz | 1.3 |  |  |  | G9 | reference layer |  |  |  | reference layer |  |  |  | G9 | reference layer |  |  |  |  |  | reference layer |  |  |  |  |  | reference layer |  |  |  |  |  | reference layer |  |  |  |  |  |
|  | Prepreg |  | 3 | 106, 71.5%*2 | 3.6 |  |  |  |  |  |  |  |  |  |  |  |  |  |  |  |  |  |  |  |  |  |  |  |  |  |  |  |  |  |  |  |  |  |  |  |
| L10 | Signal | 1 oz | 1.3 |  |  |  | S10 | 5.6(L9/L11) |  |  |  | 3.52(L9/L11) |  |  |  | S10 | 5.6(L9/L11) | 5 |  |  |  |  | 4.5(L9/L11) | 7 |  |  |  |  | 4.02(L9/L11) | 11.98 |  |  |  |  | 3.99(L9/L11) | 12.52 |  |  |  |  |
|  | Core |  | 10 | 2116, 50.2%*2 | 3.8 |  |  |  |  |  |  |  |  |  |  |  |  |  |  |  |  |  |  |  |  |  |  |  |  |  |  |  |  |  |  |  |  |  |  |  |
| L11 | GND | 1 oz | 1.3 |  |  |  | G11 | reference layer |  |  |  | reference layer |  |  |  | G11 | reference layer |  |  |  |  |  | reference layer |  |  |  |  |  | reference layer |  |  |  |  |  | reference layer |  |  |  |  |  |
|  | Prepreg |  | 3 | 106, 71.5%*2 | 3.6 |  |  |  |  |  |  |  |  |  |  |  |  |  |  |  |  |  |  |  |  |  |  |  |  |  |  |  |  |  |  |  |  |  |  |  |
| L12 | Signal | 1 oz | 1.3 |  |  |  | S12 | 5.6(L11/L13) |  |  |  | 3.52(L11/L13) |  |  |  | S12 | 5.6(L11/L13) | 5 |  |  |  |  | 4.5(L11/L13) | 7 |  |  |  |  | 4.02(L11/L13) | 11.98 |  |  |  |  | 3.99(L11/L13) | 12.52 |  |  |  |  |
|  | Core |  | 10 | 2116, 50.2%*2 | 3.8 |  |  |  |  |  |  |  |  |  |  |  |  |  |  |  |  |  |  |  |  |  |  |  |  |  |  |  |  |  |  |  |  |  |  |  |
| L13 | GND | 1 oz | 1.3 |  |  |  | G13 | reference layer |  |  |  | reference layer |  |  |  | G13 | reference layer |  |  |  |  |  | reference layer |  |  |  |  |  | reference layer |  |  |  |  |  | reference layer |  |  |  |  |  |
|  | Prepreg |  | 2.7 | 1080, 62% | 3.7 |  |  |  |  |  |  |  |  |  |  |  |  |  |  |  |  |  |  |  |  |  |  |  |  |  |  |  |  |  |  |  |  |  |  |  |
| Bottom | Signal | 0.5 oz+plating | 1.8 |  |  |  | S14 | 6.5(L13) |  |  |  | 4.25(L13) |  |  |  | S14 | 6.5(L13) | 5 |  |  |  |  | 4.5(L13) | 5 |  |  |  |  | 4.6(L13) | 13.5 |  |  |  |  | 3.95(L13) | 14.05 |  |  |  |  |
|  | Mask |  | 0.5 |  | 3.4 |  |  |  |  |  |  |  |  |  |  |  |  |  |  |  |  |  |  |  |  |  |  |  |  |  |  |  |  |  |  |  |  |  |  |  |
| Thickness requirement: 2.34 ± 9% mm |  | mil | 92.09999999999998 |  |  |  |  |  |  |  |  |  |  |  |  |  |  |  |  |  |  |  |  |  |  |  |  |  |  |  |  |  |  |  |  |  |  |  |  |  |
|  |  | mm | 2.339344678689357 |  |  |  |  |  |  |  |  |  |  |  |  |  |  |  |  |  |  |  |  |  |  |  |  |  |  |  |  |  |  |  |  |  |  |  |  |  |
| Note: | 1. Unit is mil |  |  |  |  |  |  |  |  |  |  |  |  |  |  |  |  |  |  |  |  |  |  |  |  |  |  |  |  |  |  |  |  |  |  |  |  |  |  |  |
|  | 2. The total thickness includes trace and solder mask , not G/F  area |  |  |  |  |  |  |  |  |  |  |  |  |  |  |  |  |  |  |  |  |  |  |  |  |  |  |  |  |  |  |  |  |  |  |  |  |  |  |  |
|  | 3. Min hole copper thickness is 1.0 mil |  |  |  |  |  |  |  |  |  |  |  |  |  |  |  |  |  |  |  |  |  |  |  |  |  |  |  |  |  |  |  |  |  |  |  |  |  |  |  |
|  | 4. Min surface copper thickness 1.5 mil |  |  |  |  |  |  |  |  |  |  |  |  |  |  |  |  |  |  |  |  |  |  |  |  |  |  |  |  |  |  |  |  |  |  |  |  |  |  |  |
|  | 5. Impedance Cpk requirement: >=1.33 (Report should be provided) |  |  |  |  |  |  |  |  |  |  |  |  |  |  |  |  |  |  |  |  |  |  |  |  |  |  |  |  |  |  |  |  |  |  |  |  |  |  |  |
|  | 6. PCB supplier should put Delta-L coupon gerber on main board break-away and control trace loss to meet: |  |  |  |  |  |  |  |  |  |  |  |  |  |  |  |  |  |  |  |  |  |  |  |  |  |  |  |  |  |  |  |  |  |  |  |  |  |  |  |
|  | 。  -0.65dB/inch at 4GHz for stripline routing |  |  |  |  |  |  |  |  |  |  |  |  |  |  |  |  |  |  |  |  |  |  |  |  |  |  |  |  |  |  |  |  |  |  |  |  |  |  |  |
|  | 。  -0.69dB/inch at 4GHz for microstrip routing |  |  |  |  |  |  |  |  |  |  |  |  |  |  |  |  |  |  |  |  |  |  |  |  |  |  |  |  |  |  |  |  |  |  |  |  |  |  |  |
|  | 7. The prepreq between L1 & L2 and L13 & L14 should be controlled with +/- 0.4 mil tolerance |  |  |  |  |  |  |  |  |  |  |  |  |  |  |  |  |  |  |  |  |  |  |  |  |  |  |  |  |  |  |  |  |  |  |  |  |  |  |  |
|  | 8. The prepreq between L7 & L8 should be controlled thickness min. > 5 mil |  |  |  |  |  |  |  |  |  |  |  |  |  |  |  |  |  |  |  |  |  |  |  |  |  |  |  |  |  |  |  |  |  |  |  |  |  |  |  |
|  | 9. Please keep the thickness between (L2 & L3) be target 3X of the thickness between (L3 & L4) |  |  |  |  |  |  |  |  |  |  |  |  |  |  |  |  |  |  |  |  |  |  |  |  |  |  |  |  |  |  |  |  |  |  |  |  |  |  |  |
|  | 10. Please keep the thickness between (L4 & L5) be at least 3X of the thickness between (L5 & L6) |  |  |  |  |  |  |  |  |  |  |  |  |  |  |  |  |  |  |  |  |  |  |  |  |  |  |  |  |  |  |  |  |  |  |  |  |  |  |  |
|  | 11. Please keep the thickness between (L10 & L11) be at least 3X of the thickness between (L9 & L10) |  |  |  |  |  |  |  |  |  |  |  |  |  |  |  |  |  |  |  |  |  |  |  |  |  |  |  |  |  |  |  |  |  |  |  |  |  |  |  |
|  | 12. Please keep the thickness between (L12 & L13) be at least 3X of the thickness between (L11 & L12) |  |  |  |  |  |  |  |  |  |  |  |  |  |  |  |  |  |  |  |  |  |  |  |  |  |  |  |  |  |  |  |  |  |  |  |  |  |  |  |
|  | 13. All trace width should keep +/-20% tolerance comparing with target values |  |  |  |  |  |  |  |  |  |  |  |  |  |  |  |  |  |  |  |  |  |  |  |  |  |  |  |  |  |  |  |  |  |  |  |  |  |  |  |
